# S9S_MB_2U (Grand Teton) — schematic netlist excerpt (pin names and nets, part order shuffled) for the footprints in the layout excerpt that follows; sources: Cadence DE-HDL packaged netlist, KiCad conversion of 03242023_DA0F0TMBIJ0_F0T_Motherboard_J_brd_V01_OCP.brd

PU14  RAA229126GNPHA0  RAA229126GNP#HA0 IC  pkg QFN48_THXT  page 266
  PWM0  = PVCCFA_EHV_FIVRA_CPU0_PWM1
  PWM1  = PVCCFA_EHV_FIVRA_CPU0_PWM2
  PWM2  = PVCCFA_EHV_FIVRA_CPU0_PWM3
  PWM3  = PVCCFA_EHV_FIVRA_CPU0_PWM4
  PWM4  = PVCCIN_CPU0_PWM8
  PWM5  = PVCCIN_CPU0_PWM7
  PWM6  = PVCCIN_CPU0_PWM6
  PWM7  = PVCCIN_CPU0_PWM5
  PWM8  = PVCCIN_CPU0_PWM4
  PWM9  = PVCCIN_CPU0_PWM3
  PWM10  = PVCCIN_CPU0_PWM2
  PWM11  = PVCCIN_CPU0_PWM1
  PMSDA  = SMB_DIO_PVCCIN_CPU0
  PMSCL  = SMB_CLK_PVCCIN_CPU0
  NPMALERT  = NC_PVCCIN_CPU0_SMB_ALERT
  PG0  = PWRGD_PVCCIN_CPU0_R
  EN0  = PVCCIN_CPU0_EN_R
  NVRHOT  = IRQ_PVCCIN_CPU0_VRHOT_N
  \npinalert||npsys_crit\  = PVCCIN_CPU0_PIN_ALERT
  PG1  = PWRGD_PVCCFA_EHV_FIVRA_CPU0_R
  SVCLK  = SVID_CLK_PVCCIN_CPU0_R
  SVDATA  = SVID_DIO_PVCCIN_CPU0_R
  NSVALERT  = SVID_ALERT_PVCCIN_CPU0_R
  EN1  = PVCCFA_EHV_FIVRA_CPU0_EN_R
  VSEN0  = SH_PVCCIN_CPU0_R
  RGND0  = VSENSE_PVCCIN_CPU0_DN
  CS11  = PVCCIN_CPU0_IMON1
  CS10  = PVCCIN_CPU0_IMON2
  CS9  = PVCCIN_CPU0_IMON3
  CS8  = PVCCIN_CPU0_IMON4
  CS7  = PVCCIN_CPU0_IMON5
  CS6  = PVCCIN_CPU0_IMON6
  CS5  = PVCCIN_CPU0_IMON7
  CS4  = PVCCIN_CPU0_IMON8
  CS3  = PVCCFA_EHV_FIVRA_CPU0_IMON4
  CS2  = PVCCFA_EHV_FIVRA_CPU0_IMON3
  CS1  = PVCCFA_EHV_FIVRA_CPU0_IMON2
  CS0  = PVCCFA_EHV_FIVRA_CPU0_IMON1
  RGND1  = VSENSE_PVCCFA_EHV_FIVRA_CPU0_DN
  VSEN1  = SH_PVCCFA_EHV_FIVRA_CPU0_R
  CFP  = PVCCIN_CPU0_VR_FAULT
  ADDR_CFG  = PVCCIN_CPU0_ADDR
  TEMP0  = PVCCIN_CPU0_ATSEN
  \temp1||isys\  = PVCCFA_EHV_FIVRA_CPU0_BTSEN
  \vmon||iinsen||vsys||isys\  = PVCCIN_CPU0_CSPIN
  \vinsen||vsys\  = PVCCIN_CPU0_VIN_CSNIN
  VCC  = PVCCIN_CPU0_VCC
  VCCS  = PVCCIN_CPU0_VREF
  TH_GND  = GND

(kicad_pcb
	(version 20260206)
	(generator "pcbnew")
	(generator_version "10.0")
	(general
		(thickness 1.6)
		(legacy_teardrops no)
	)
	(paper "A4")
	(title_block
		(title "03242023_DA0F0TMBIJ0_F0T_Motherboard_J_brd_V01_OCP.brd")
		(comment 1 "Grand Teton / footprint 2912 of 6105 (PU14), pads 43-49 of 49")
	)
	(layers
		(0 "F.Cu" signal "TOP")
		(4 "In1.Cu" signal "GND")
		(6 "In2.Cu" signal "IN1")
		(8 "In3.Cu" signal "GND1")
		(10 "In4.Cu" signal "IN2")
		(12 "In5.Cu" signal "GND2")
		(14 "In6.Cu" signal "IN3")
		(16 "In7.Cu" signal "GND3")
		(18 "In8.Cu" signal "VCC")
		(20 "In9.Cu" signal "VCC1")
		(22 "In10.Cu" signal "GND4")
		(24 "In11.Cu" signal "IN4")
		(26 "In12.Cu" signal "GND5")
		(28 "In13.Cu" signal "IN5")
		(30 "In14.Cu" signal "GND6")
		(32 "In15.Cu" signal "IN6")
		(34 "In16.Cu" signal "GND7")
		(2 "B.Cu" signal "BOTTOM")
		(9 "F.Adhes" user "F.Adhesive")
		(11 "B.Adhes" user "B.Adhesive")
		(13 "F.Paste" user "Package Geometry/Pastemask Top")
		(15 "B.Paste" user "Package Geometry/Pastemask Bottom")
		(5 "F.SilkS" user "Ref Des/Silkscreen Top")
		(7 "B.SilkS" user "Ref Des/Silkscreen Bottom")
		(1 "F.Mask" user "Board Geometry/Soldermask Top")
		(3 "B.Mask" user "Board Geometry/Soldermask Bottom")
		(17 "Dwgs.User" user "User.Drawings")
		(19 "Cmts.User" user "User.Comments")
		(21 "Eco1.User" user "User.Eco1")
		(23 "Eco2.User" user "User.Eco2")
		(25 "Edge.Cuts" user "Board Geometry/Outline")
		(27 "Margin" user)
		(31 "F.CrtYd" user "Package Geometry/Place Bound Top")
		(29 "B.CrtYd" user "Package Geometry/Place Bound Bottom")
		(35 "F.Fab" user "Ref Des/Assembly Top")
		(33 "B.Fab" user "Ref Des/Assembly Bottom")
	)
	(footprint ""
		(layer "F.Cu")
		(at 356.51821 -358.848406 -90)
		(property "Reference" "PU14"
			(at -7.271512 3.70967 0)
			(unlocked yes)
			(layer "F.SilkS")
			(effects
				(font
					(size 0.7874 0.5842)
					(thickness 0.1524)
				)
				(justify left)
			)
		)
		(property "Value" ""
			(at 0 0 270)
			(layer "F.Fab")
			(effects
				(font
					(size 1.27 1.27)
				)
			)
		)
		(duplicate_pad_numbers_are_jumpers no)
		(pad "43" smd rect
			(at -0.199898 -2.875026 270)
			(size 0.1778 0.6604)
			(layers "F.Cu" "F.Mask" "F.Paste")
			(net "PVCCIN_CPU0_ATSEN")
		)
		(pad "44" smd rect
			(at -0.599948 -2.875026 270)
			(size 0.1778 0.6604)
			(layers "F.Cu" "F.Mask" "F.Paste")
			(net "PVCCFA_EHV_FIVRA_CPU0_BTSEN")
		)
		(pad "45" smd rect
			(at -0.999998 -2.875026 270)
			(size 0.1778 0.6604)
			(layers "F.Cu" "F.Mask" "F.Paste")
			(net "PVCCIN_CPU0_CSPIN")
		)
		(pad "46" smd rect
			(at -1.400048 -2.875026 270)
			(size 0.1778 0.6604)
			(layers "F.Cu" "F.Mask" "F.Paste")
			(net "PVCCIN_CPU0_VIN_CSNIN")
		)
		(pad "47" smd rect
			(at -1.800098 -2.875026 270)
			(size 0.1778 0.6604)
			(layers "F.Cu" "F.Mask" "F.Paste")
			(net "PVCCIN_CPU0_VCC")
		)
		(pad "48" smd rect
			(at -2.199894 -2.875026 270)
			(size 0.1778 0.6604)
			(layers "F.Cu" "F.Mask" "F.Paste")
			(net "PVCCIN_CPU0_VREF")
		)
		(pad "TH" smd rect
			(at 0 0 270)
			(size 4.4196 4.4196)
			(layers "F.Cu" "F.Mask" "F.Paste")
			(net "GND")
		)
	)
)
